# BASEBOARD_FAB2 (Tioga Pass) — schematic netlist excerpt (pin names and nets, part order shuffled) for the footprints in the layout excerpt that follows; sources: Cadence DE-HDL packaged netlist, KiCad conversion of Wiwynn_Tioga_Pass_MB.brd

R7G24  RES  150.0 1% CHIP  pkg 0402  page 215 : A = SVID_CLK1_CPU0_R ; B = SVID_CLK_PVDDQ_ABC
CT1  CAP_A  0.1UF 16V 10% X7R  pkg 0402V  page 202 : A = VR_PVCCIN_CPU0_AIREF1 ; B = GND
R4D28  RES  27.4 1% CHIP  pkg 0402  page 103 : A = CLK_100M_CPU1_RC_REFCLK1_R_DN ; B = CLK_100M_CPU1_RC_REFCLK1_DN

(kicad_pcb
	(version 20260206)
	(generator "pcbnew")
	(generator_version "10.0")
	(general
		(thickness 1.6)
		(legacy_teardrops no)
	)
	(paper "A4")
	(title_block
		(title "Wiwynn_Tioga_Pass_MB.brd")
		(comment 1 "Tioga Pass / footprints 28-30 of 4770")
	)
	(layers
		(0 "F.Cu" signal "TOP")
		(4 "In1.Cu" signal "L2GND")
		(6 "In2.Cu" signal "L3")
		(8 "In3.Cu" signal "L4GND")
		(10 "In4.Cu" signal "L5")
		(12 "In5.Cu" signal "L6GND")
		(14 "In6.Cu" signal "L7VCC")
		(16 "In7.Cu" signal "L8VCC")
		(18 "In8.Cu" signal "L9GND")
		(20 "In9.Cu" signal "L10")
		(22 "In10.Cu" signal "L11GND")
		(24 "In11.Cu" signal "L12")
		(26 "In12.Cu" signal "L13GND")
		(2 "B.Cu" signal "BOTTOM")
		(9 "F.Adhes" user "F.Adhesive")
		(11 "B.Adhes" user "B.Adhesive")
		(13 "F.Paste" user "Package Geometry/Pastemask Top")
		(15 "B.Paste" user "Package Geometry/Pastemask Bottom")
		(5 "F.SilkS" user "Ref Des/Silkscreen Top")
		(7 "B.SilkS" user "Ref Des/Silkscreen Bottom")
		(1 "F.Mask" user "Board Geometry/Soldermask Top")
		(3 "B.Mask" user "Board Geometry/Soldermask Bottom")
		(17 "Dwgs.User" user "User.Drawings")
		(19 "Cmts.User" user "User.Comments")
		(21 "Eco1.User" user "User.Eco1")
		(23 "Eco2.User" user "User.Eco2")
		(25 "Edge.Cuts" user "Board Geometry/Outline")
		(27 "Margin" user)
		(31 "F.CrtYd" user "Package Geometry/Place Bound Top")
		(29 "B.CrtYd" user "Package Geometry/Place Bound Bottom")
		(35 "F.Fab" user "Ref Des/Assembly Top")
		(33 "B.Fab" user "Ref Des/Assembly Bottom")
	)
	(footprint ""
		(layer "F.Cu")
		(at 194.804538 -53.48478)
		(property "Reference" "CT1"
			(at -0.762 2.26187 0)
			(unlocked yes)
			(layer "F.SilkS")
			(effects
				(font
					(size 0.7874 0.5842)
					(thickness 0.1524)
				)
				(justify left)
			)
		)
		(property "Value" ""
			(at 0 0 0)
			(layer "F.Fab")
			(effects
				(font
					(size 1.27 1.27)
				)
			)
		)
		(duplicate_pad_numbers_are_jumpers no)
		(fp_poly
			(pts
				(xy 0.3048 -0.1016) (xy 0.3048 0.9906) (xy -0.3048 0.9906) (xy -0.3048 -0.1016)
			)
			(stroke
				(width 0)
				(type default)
			)
			(fill no)
			(layer "F.CrtYd")
		)
		(fp_line
			(start -0.3048 -0.1016)
			(end -0.3048 0.9906)
			(stroke
				(width 0.1)
				(type default)
			)
			(layer "F.Fab")
		)
		(fp_line
			(start -0.3048 0.9906)
			(end 0.3048 0.9906)
			(stroke
				(width 0.1)
				(type default)
			)
			(layer "F.Fab")
		)
		(fp_line
			(start 0.3048 -0.1016)
			(end -0.3048 -0.1016)
			(stroke
				(width 0.1)
				(type default)
			)
			(layer "F.Fab")
		)
		(fp_line
			(start 0.3048 0.9906)
			(end 0.3048 -0.1016)
			(stroke
				(width 0.1)
				(type default)
			)
			(layer "F.Fab")
		)
		(pad "1" smd rect
			(at 0 0)
			(size 0.508 0.508)
			(layers "F.Cu" "F.Mask" "F.Paste")
			(net "VR_PVCCIN_CPU0_AIREF1")
		)
		(pad "2" smd rect
			(at 0 0.889)
			(size 0.508 0.508)
			(layers "F.Cu" "F.Mask" "F.Paste")
			(net "GND")
		)
		(zone
			(layer "F.Cu")
			(hatch none 0.5)
			(connect_pads
				(clearance 0)
			)
			(min_thickness 0.25)
			(keepout
				(tracks allowed)
				(vias not_allowed)
				(pads allowed)
				(copperpour not_allowed)
				(footprints allowed)
			)
			(placement
				(enabled no)
				(sheetname "")
			)
			(fill
				(thermal_gap 0.5)
				(thermal_bridge_width 0.5)
				(island_removal_mode 0)
			)
			(polygon
				(pts
					(xy 194.550538 -53.23078) (xy 195.058538 -53.23078) (xy 195.058538 -52.84978) (xy 194.550538 -52.84978)
				)
			)
		)
		(zone
			(layer "F.Cu")
			(hatch none 0.5)
			(connect_pads
				(clearance 0)
			)
			(min_thickness 0.25)
			(keepout
				(tracks not_allowed)
				(vias allowed)
				(pads allowed)
				(copperpour not_allowed)
				(footprints allowed)
			)
			(placement
				(enabled no)
				(sheetname "")
			)
			(fill
				(thermal_gap 0.5)
				(thermal_bridge_width 0.5)
				(island_removal_mode 0)
			)
			(polygon
				(pts
					(xy 194.550538 -52.84978) (xy 195.058538 -52.84978) (xy 195.058538 -53.23078) (xy 194.550538 -53.23078)
				)
			)
		)
	)
	(footprint ""
		(layer "F.Cu")
		(at 337.947 -17.272 90)
		(property "Reference" "R7G24"
			(at 0 0 90)
			(layer "F.SilkS")
			(hide yes)
			(effects
				(font
					(size 1.27 1.27)
				)
			)
		)
		(property "Value" ""
			(at 0 0 90)
			(layer "F.Fab")
			(effects
				(font
					(size 1.27 1.27)
				)
			)
		)
		(duplicate_pad_numbers_are_jumpers no)
		(fp_rect
			(start -0.2794 -0.1016)
			(end 0.2794 0.9906)
			(stroke
				(width 0)
				(type default)
			)
			(fill no)
			(layer "F.CrtYd")
		)
		(fp_line
			(start 0.2794 -0.1016)
			(end -0.2794 -0.1016)
			(stroke
				(width 0.1)
				(type default)
			)
			(layer "F.Fab")
		)
		(fp_line
			(start -0.2794 -0.1016)
			(end -0.2794 0.9906)
			(stroke
				(width 0.1)
				(type default)
			)
			(layer "F.Fab")
		)
		(fp_line
			(start 0.2794 0.9906)
			(end 0.2794 -0.1016)
			(stroke
				(width 0.1)
				(type default)
			)
			(layer "F.Fab")
		)
		(fp_line
			(start -0.2794 0.9906)
			(end 0.2794 0.9906)
			(stroke
				(width 0.1)
				(type default)
			)
			(layer "F.Fab")
		)
		(pad "1" smd rect
			(at 0 0 90)
			(size 0.508 0.508)
			(layers "F.Cu" "F.Mask" "F.Paste")
			(net "SVID_CLK1_CPU0_R")
		)
		(pad "2" smd rect
			(at 0 0.889 90)
			(size 0.508 0.508)
			(layers "F.Cu" "F.Mask" "F.Paste")
			(net "SVID_CLK_PVDDQ_ABC")
		)
		(zone
			(layer "F.Cu")
			(hatch none 0.5)
			(connect_pads
				(clearance 0)
			)
			(min_thickness 0.25)
			(keepout
				(tracks not_allowed)
				(vias allowed)
				(pads allowed)
				(copperpour not_allowed)
				(footprints allowed)
			)
			(placement
				(enabled no)
				(sheetname "")
			)
			(fill
				(thermal_gap 0.5)
				(thermal_bridge_width 0.5)
				(island_removal_mode 0)
			)
			(polygon
				(pts
					(xy 338.201 -17.018) (xy 338.582 -17.018) (xy 338.582 -17.526) (xy 338.201 -17.526)
				)
			)
		)
		(zone
			(layer "F.Cu")
			(hatch none 0.5)
			(connect_pads
				(clearance 0)
			)
			(min_thickness 0.25)
			(keepout
				(tracks allowed)
				(vias not_allowed)
				(pads allowed)
				(copperpour not_allowed)
				(footprints allowed)
			)
			(placement
				(enabled no)
				(sheetname "")
			)
			(fill
				(thermal_gap 0.5)
				(thermal_bridge_width 0.5)
				(island_removal_mode 0)
			)
			(polygon
				(pts
					(xy 338.201 -17.018) (xy 338.582 -17.018) (xy 338.582 -17.526) (xy 338.201 -17.526)
				)
			)
		)
	)
	(footprint ""
		(layer "F.Cu")
		(at 163.576 -76.708 -90)
		(property "Reference" "R4D28"
			(at 0 0 270)
			(layer "F.SilkS")
			(hide yes)
			(effects
				(font
					(size 1.27 1.27)
				)
			)
		)
		(property "Value" ""
			(at 0 0 270)
			(layer "F.Fab")
			(effects
				(font
					(size 1.27 1.27)
				)
			)
		)
		(duplicate_pad_numbers_are_jumpers no)
		(fp_poly
			(pts
				(xy -0.2794 -0.1016) (xy 0.2794 -0.1016) (xy 0.2794 0.9906) (xy -0.2794 0.9906)
			)
			(stroke
				(width 0)
				(type default)
			)
			(fill no)
			(layer "F.CrtYd")
		)
		(fp_line
			(start -0.2794 0.9906)
			(end 0.2794 0.9906)
			(stroke
				(width 0.1)
				(type default)
			)
			(layer "F.Fab")
		)
		(fp_line
			(start 0.2794 0.9906)
			(end 0.2794 -0.1016)
			(stroke
				(width 0.1)
				(type default)
			)
			(layer "F.Fab")
		)
		(fp_line
			(start -0.2794 -0.1016)
			(end -0.2794 0.9906)
			(stroke
				(width 0.1)
				(type default)
			)
			(layer "F.Fab")
		)
		(fp_line
			(start 0.2794 -0.1016)
			(end -0.2794 -0.1016)
			(stroke
				(width 0.1)
				(type default)
			)
			(layer "F.Fab")
		)
		(pad "1" smd rect
			(at 0 0 270)
			(size 0.508 0.508)
			(layers "F.Cu" "F.Mask" "F.Paste")
			(net "CLK_100M_CPU1_RC_REFCLK1_R_DN")
		)
		(pad "2" smd rect
			(at 0 0.889 270)
			(size 0.508 0.508)
			(layers "F.Cu" "F.Mask" "F.Paste")
			(net "CLK_100M_CPU1_RC_REFCLK1_DN")
		)
		(zone
			(layer "F.Cu")
			(hatch none 0.5)
			(connect_pads
				(clearance 0)
			)
			(min_thickness 0.25)
			(keepout
				(tracks not_allowed)
				(vias allowed)
				(pads allowed)
				(copperpour not_allowed)
				(footprints allowed)
			)
			(placement
				(enabled no)
				(sheetname "")
			)
			(fill
				(thermal_gap 0.5)
				(thermal_bridge_width 0.5)
				(island_removal_mode 0)
			)
			(polygon
				(pts
					(xy 162.941 -76.962) (xy 162.941 -76.454) (xy 163.322 -76.454) (xy 163.322 -76.962)
				)
			)
		)
		(zone
			(layer "F.Cu")
			(hatch none 0.5)
			(connect_pads
				(clearance 0)
			)
			(min_thickness 0.25)
			(keepout
				(tracks allowed)
				(vias not_allowed)
				(pads allowed)
				(copperpour not_allowed)
				(footprints allowed)
			)
			(placement
				(enabled no)
				(sheetname "")
			)
			(fill
				(thermal_gap 0.5)
				(thermal_bridge_width 0.5)
				(island_removal_mode 0)
			)
			(polygon
				(pts
					(xy 163.322 -76.962) (xy 163.322 -76.454) (xy 162.941 -76.454) (xy 162.941 -76.962)
				)
			)
		)
	)
)
